#ISCELL
  cls sheet_a1 *
  *
#CELL
  passive resistor *
  page6_i100
#ISCELL
  cls offpage_bi *
  page6_i12
#ISCELL
  cls offpage_bi *
  page6_i13
#CELL
  passive resistor *
  page6_i14
#CELL
  passive resistor *
  page6_i15
#CELL
  passive resistor *
  page6_i16
#ISCELL
  cls gnd_sg *
  page6_i29
#CELL
  passive resistor *
  page6_i30
#CELL
  passive resistor *
  page6_i31
#CELL
  passive resistor *
  page6_i32
#CELL
  passive resistor *
  page6_i33
#CELL
  interface lm75bdp_tssop8 *
  page6_i34
#CELL
  passive resistor *
  page6_i35
#CELL
  passive resistor *
  page6_i36
#CELL
  passive capacitor *
  page6_i37
#CELL
  interface lm75bdp_tssop8 *
  page6_i38
#CELL
  passive resistor *
  page6_i41
#ISCELL
  cls offpage_out *
  page6_i44
#ISCELL
  cls gnd_sg *
  page6_i45
#ISCELL
  cls vcc *
  page6_i56
#ISCELL
  cls vcc *
  page6_i57
#ISCELL
  cls vcc *
  page6_i58
#CELL
  interface lm75bdp_tssop8 *
  page6_i59
#CELL
  passive resistor *
  page6_i60
#ISCELL
  cls offpage_out *
  page6_i61
#ISCELL
  cls vcc *
  page6_i62
#ISCELL
  cls vcc *
  page6_i63
#CELL
  passive resistor *
  page6_i64
#CELL
  interface lm75bdp_tssop8 *
  page6_i66
#CELL
  passive capacitor *
  page6_i67
#ISCELL
  cls gnd_sg *
  page6_i68
#CELL
  passive resistor *
  page6_i69
#CELL
  passive resistor *
  page6_i70
#CELL
  passive resistor *
  page6_i71
#CELL
  passive resistor *
  page6_i72
#CELL
  passive resistor *
  page6_i73
#ISCELL
  cls gnd_sg *
  page6_i74
#CELL
  passive resistor *
  page6_i76
#ISCELL
  cls vcc *
  page6_i77
#CELL
  interface lm75bdp_tssop8 *
  page6_i81
#ISCELL
  cls offpage_out *
  page6_i82
#ISCELL
  cls vcc *
  page6_i83
#CELL
  passive resistor *
  page6_i84
#CELL
  passive resistor *
  page6_i85
#CELL
  passive resistor *
  page6_i86
#ISCELL
  cls vcc *
  page6_i87
#CELL
  passive resistor *
  page6_i88
#CELL
  interface lm75bdp_tssop8 *
  page6_i90
#CELL
  passive capacitor *
  page6_i91
#ISCELL
  cls gnd_sg *
  page6_i92
#CELL
  passive resistor *
  page6_i93
#CELL
  passive resistor *
  page6_i94
#CELL
  passive resistor *
  page6_i95
#ISCELL
  cls gnd_sg *
  page6_i96
#ISCELL
  cls vcc *
  page6_i98
